(kicad_pcb
	(version 20260206)
	(generator "pcbnew")
	(generator_version "10.0")
	(general
		(thickness 1.6)
		(legacy_teardrops no)
	)
	(paper "A4")
	(title_block
		(title "12092022_DA0F0TMDCD0_F0T_Management_Board_D_brd_V3_OCP.brd")
		(comment 1 "Grand Teton / footprints 19-24 of 1440")
	)
	(layers
		(0 "F.Cu" signal "TOP")
		(4 "In1.Cu" signal "GND")
		(6 "In2.Cu" signal "IN1")
		(8 "In3.Cu" signal "GND1")
		(10 "In4.Cu" signal "IN2")
		(12 "In5.Cu" signal "VCC")
		(14 "In6.Cu" signal "VCC1")
		(16 "In7.Cu" signal "IN3")
		(18 "In8.Cu" signal "GND2")
		(20 "In9.Cu" signal "IN4")
		(22 "In10.Cu" signal "GND3")
		(2 "B.Cu" signal "BOTTOM")
		(9 "F.Adhes" user "F.Adhesive")
		(11 "B.Adhes" user "B.Adhesive")
		(13 "F.Paste" user "Package Geometry/Pastemask Top")
		(15 "B.Paste" user "Package Geometry/Pastemask Bottom")
		(5 "F.SilkS" user "Ref Des/Silkscreen Top")
		(7 "B.SilkS" user "Ref Des/Silkscreen Bottom")
		(1 "F.Mask" user "Board Geometry/Soldermask Top")
		(3 "B.Mask" user "Board Geometry/Soldermask Bottom")
		(17 "Dwgs.User" user "User.Drawings")
		(19 "Cmts.User" user "User.Comments")
		(21 "Eco1.User" user "User.Eco1")
		(23 "Eco2.User" user "User.Eco2")
		(25 "Edge.Cuts" user "Board Geometry/Outline")
		(27 "Margin" user)
		(31 "F.CrtYd" user "Package Geometry/Place Bound Top")
		(29 "B.CrtYd" user "Package Geometry/Place Bound Bottom")
		(35 "F.Fab" user "Ref Des/Assembly Top")
		(33 "B.Fab" user "Ref Des/Assembly Bottom")
	)
	(footprint ""
		(layer "F.Cu")
		(at 47.2694 -74.803 180)
		(property "Reference" "C312"
			(at 0 0 180)
			(layer "F.SilkS")
			(hide yes)
			(effects
				(font
					(size 1.27 1.27)
				)
			)
		)
		(property "Value" ""
			(at 0 0 180)
			(layer "F.Fab")
			(effects
				(font
					(size 1.27 1.27)
				)
			)
		)
		(duplicate_pad_numbers_are_jumpers no)
		(fp_line
			(start 0.7874 0.4064)
			(end -0.7874 0.4064)
			(stroke
				(width 0.1524)
				(type default)
			)
			(layer "F.SilkS")
		)
		(fp_line
			(start 0.7874 -0.4064)
			(end 0.7874 0.4064)
			(stroke
				(width 0.1524)
				(type default)
			)
			(layer "F.SilkS")
		)
		(fp_line
			(start -0.7874 0.4064)
			(end -0.7874 -0.4064)
			(stroke
				(width 0.1524)
				(type default)
			)
			(layer "F.SilkS")
		)
		(fp_line
			(start -0.7874 -0.4064)
			(end 0.7874 -0.4064)
			(stroke
				(width 0.1524)
				(type default)
			)
			(layer "F.SilkS")
		)
		(fp_line
			(start 0.67945 0.3048)
			(end 0.120396 0.3048)
			(stroke
				(width 0.1)
				(type default)
			)
			(layer "F.Fab")
		)
		(fp_line
			(start 0.67945 -0.3048)
			(end 0.67945 0.3048)
			(stroke
				(width 0.1)
				(type default)
			)
			(layer "F.Fab")
		)
		(fp_line
			(start 0.12065 -0.2794)
			(end 0.12065 -0.3048)
			(stroke
				(width 0.1)
				(type default)
			)
			(layer "F.Fab")
		)
		(fp_line
			(start 0.12065 -0.3048)
			(end 0.67945 -0.3048)
			(stroke
				(width 0.1)
				(type default)
			)
			(layer "F.Fab")
		)
		(fp_line
			(start 0.120396 0.3048)
			(end 0.120396 0.2794)
			(stroke
				(width 0.1)
				(type default)
			)
			(layer "F.Fab")
		)
		(fp_line
			(start 0.120396 0.2794)
			(end -0.12065 0.2794)
			(stroke
				(width 0.1)
				(type default)
			)
			(layer "F.Fab")
		)
		(fp_line
			(start -0.12065 0.3048)
			(end -0.67945 0.3048)
			(stroke
				(width 0.1)
				(type default)
			)
			(layer "F.Fab")
		)
		(fp_line
			(start -0.12065 0.2794)
			(end -0.12065 0.3048)
			(stroke
				(width 0.1)
				(type default)
			)
			(layer "F.Fab")
		)
		(fp_line
			(start -0.12065 -0.2794)
			(end 0.12065 -0.2794)
			(stroke
				(width 0.1)
				(type default)
			)
			(layer "F.Fab")
		)
		(fp_line
			(start -0.12065 -0.305054)
			(end -0.12065 -0.2794)
			(stroke
				(width 0.1)
				(type default)
			)
			(layer "F.Fab")
		)
		(fp_line
			(start -0.67945 0.3048)
			(end -0.67945 -0.305054)
			(stroke
				(width 0.1)
				(type default)
			)
			(layer "F.Fab")
		)
		(fp_line
			(start -0.67945 -0.305054)
			(end -0.12065 -0.305054)
			(stroke
				(width 0.1)
				(type default)
			)
			(layer "F.Fab")
		)
		(pad "1" smd circle
			(at -0.40005 0 180)
			(size 0 0)
			(layers "F.Cu" "F.Mask" "F.Paste")
			(net "P3V3_AUX")
		)
		(pad "2" smd circle
			(at 0.40005 0 180)
			(size 0 0)
			(layers "F.Cu" "F.Mask" "F.Paste")
			(net "GND")
		)
	)
	(footprint ""
		(layer "F.Cu")
		(at 45.085 -82.6008)
		(property "Reference" "R556"
			(at 0 0 0)
			(layer "F.SilkS")
			(hide yes)
			(effects
				(font
					(size 1.27 1.27)
				)
			)
		)
		(property "Value" ""
			(at 0 0 0)
			(layer "F.Fab")
			(effects
				(font
					(size 1.27 1.27)
				)
			)
		)
		(duplicate_pad_numbers_are_jumpers no)
		(fp_line
			(start -0.7874 -0.4064)
			(end 0.7874 -0.4064)
			(stroke
				(width 0.1524)
				(type default)
			)
			(layer "F.SilkS")
		)
		(fp_line
			(start -0.7874 0.4064)
			(end -0.7874 -0.4064)
			(stroke
				(width 0.1524)
				(type default)
			)
			(layer "F.SilkS")
		)
		(fp_line
			(start 0.7874 -0.4064)
			(end 0.7874 0.4064)
			(stroke
				(width 0.1524)
				(type default)
			)
			(layer "F.SilkS")
		)
		(fp_line
			(start 0.7874 0.4064)
			(end -0.7874 0.4064)
			(stroke
				(width 0.1524)
				(type default)
			)
			(layer "F.SilkS")
		)
		(fp_line
			(start -0.67945 -0.305054)
			(end -0.12065 -0.305054)
			(stroke
				(width 0.1)
				(type default)
			)
			(layer "F.Fab")
		)
		(fp_line
			(start -0.67945 0.3048)
			(end -0.67945 -0.305054)
			(stroke
				(width 0.1)
				(type default)
			)
			(layer "F.Fab")
		)
		(fp_line
			(start -0.12065 -0.305054)
			(end -0.12065 -0.2794)
			(stroke
				(width 0.1)
				(type default)
			)
			(layer "F.Fab")
		)
		(fp_line
			(start -0.12065 -0.2794)
			(end 0.12065 -0.2794)
			(stroke
				(width 0.1)
				(type default)
			)
			(layer "F.Fab")
		)
		(fp_line
			(start -0.12065 0.2794)
			(end -0.12065 0.3048)
			(stroke
				(width 0.1)
				(type default)
			)
			(layer "F.Fab")
		)
		(fp_line
			(start -0.12065 0.3048)
			(end -0.67945 0.3048)
			(stroke
				(width 0.1)
				(type default)
			)
			(layer "F.Fab")
		)
		(fp_line
			(start 0.120396 0.2794)
			(end -0.12065 0.2794)
			(stroke
				(width 0.1)
				(type default)
			)
			(layer "F.Fab")
		)
		(fp_line
			(start 0.120396 0.3048)
			(end 0.120396 0.2794)
			(stroke
				(width 0.1)
				(type default)
			)
			(layer "F.Fab")
		)
		(fp_line
			(start 0.12065 -0.3048)
			(end 0.67945 -0.3048)
			(stroke
				(width 0.1)
				(type default)
			)
			(layer "F.Fab")
		)
		(fp_line
			(start 0.12065 -0.2794)
			(end 0.12065 -0.3048)
			(stroke
				(width 0.1)
				(type default)
			)
			(layer "F.Fab")
		)
		(fp_line
			(start 0.67945 -0.3048)
			(end 0.67945 0.3048)
			(stroke
				(width 0.1)
				(type default)
			)
			(layer "F.Fab")
		)
		(fp_line
			(start 0.67945 0.3048)
			(end 0.120396 0.3048)
			(stroke
				(width 0.1)
				(type default)
			)
			(layer "F.Fab")
		)
		(pad "1" smd circle
			(at -0.40005 0)
			(size 0 0)
			(layers "F.Cu" "F.Mask" "F.Paste")
			(net "SPI_BMC_BT_WP1_N_R")
		)
		(pad "2" smd circle
			(at 0.40005 0)
			(size 0 0)
			(layers "F.Cu" "F.Mask" "F.Paste")
			(net "FLASH_LATCH_Q_N_R2")
		)
	)
	(footprint ""
		(layer "F.Cu")
		(at 13.335 -18.161 -90)
		(property "Reference" "R839"
			(at 0 0 270)
			(layer "F.SilkS")
			(hide yes)
			(effects
				(font
					(size 1.27 1.27)
				)
			)
		)
		(property "Value" ""
			(at 0 0 270)
			(layer "F.Fab")
			(effects
				(font
					(size 1.27 1.27)
				)
			)
		)
		(duplicate_pad_numbers_are_jumpers no)
		(fp_line
			(start -0.7874 0.4064)
			(end -0.7874 -0.4064)
			(stroke
				(width 0.1524)
				(type default)
			)
			(layer "F.SilkS")
		)
		(fp_line
			(start 0.7874 0.4064)
			(end -0.7874 0.4064)
			(stroke
				(width 0.1524)
				(type default)
			)
			(layer "F.SilkS")
		)
		(fp_line
			(start -0.7874 -0.4064)
			(end 0.7874 -0.4064)
			(stroke
				(width 0.1524)
				(type default)
			)
			(layer "F.SilkS")
		)
		(fp_line
			(start 0.7874 -0.4064)
			(end 0.7874 0.4064)
			(stroke
				(width 0.1524)
				(type default)
			)
			(layer "F.SilkS")
		)
		(fp_line
			(start -0.67945 0.3048)
			(end -0.67945 -0.305054)
			(stroke
				(width 0.1)
				(type default)
			)
			(layer "F.Fab")
		)
		(fp_line
			(start -0.12065 0.3048)
			(end -0.67945 0.3048)
			(stroke
				(width 0.1)
				(type default)
			)
			(layer "F.Fab")
		)
		(fp_line
			(start 0.120396 0.3048)
			(end 0.120396 0.2794)
			(stroke
				(width 0.1)
				(type default)
			)
			(layer "F.Fab")
		)
		(fp_line
			(start 0.67945 0.3048)
			(end 0.120396 0.3048)
			(stroke
				(width 0.1)
				(type default)
			)
			(layer "F.Fab")
		)
		(fp_line
			(start -0.12065 0.2794)
			(end -0.12065 0.3048)
			(stroke
				(width 0.1)
				(type default)
			)
			(layer "F.Fab")
		)
		(fp_line
			(start 0.120396 0.2794)
			(end -0.12065 0.2794)
			(stroke
				(width 0.1)
				(type default)
			)
			(layer "F.Fab")
		)
		(fp_line
			(start -0.12065 -0.2794)
			(end 0.12065 -0.2794)
			(stroke
				(width 0.1)
				(type default)
			)
			(layer "F.Fab")
		)
		(fp_line
			(start 0.12065 -0.2794)
			(end 0.12065 -0.3048)
			(stroke
				(width 0.1)
				(type default)
			)
			(layer "F.Fab")
		)
		(fp_line
			(start 0.12065 -0.3048)
			(end 0.67945 -0.3048)
			(stroke
				(width 0.1)
				(type default)
			)
			(layer "F.Fab")
		)
		(fp_line
			(start 0.67945 -0.3048)
			(end 0.67945 0.3048)
			(stroke
				(width 0.1)
				(type default)
			)
			(layer "F.Fab")
		)
		(fp_line
			(start -0.67945 -0.305054)
			(end -0.12065 -0.305054)
			(stroke
				(width 0.1)
				(type default)
			)
			(layer "F.Fab")
		)
		(fp_line
			(start -0.12065 -0.305054)
			(end -0.12065 -0.2794)
			(stroke
				(width 0.1)
				(type default)
			)
			(layer "F.Fab")
		)
		(pad "1" smd circle
			(at -0.40005 0 270)
			(size 0 0)
			(layers "F.Cu" "F.Mask" "F.Paste")
			(net "PWR_LED")
		)
		(pad "2" smd circle
			(at 0.40005 0 270)
			(size 0 0)
			(layers "F.Cu" "F.Mask" "F.Paste")
			(net "GND")
		)
	)
	(footprint ""
		(layer "F.Cu")
		(at 17.47774 -42.72534 90)
		(property "Reference" "U44"
			(at -0.94234 -1.70307 90)
			(unlocked yes)
			(layer "F.SilkS")
			(effects
				(font
					(size 0.7874 0.5842)
					(thickness 0.1524)
				)
				(justify left)
			)
		)
		(property "Value" ""
			(at 0 0 90)
			(layer "F.Fab")
			(effects
				(font
					(size 1.27 1.27)
				)
			)
		)
		(duplicate_pad_numbers_are_jumpers no)
		(fp_line
			(start 1.684274 -1.074928)
			(end 1.684274 1.074928)
			(stroke
				(width 0.1524)
				(type default)
			)
			(layer "F.SilkS")
		)
		(fp_line
			(start 0.381 -1.074928)
			(end 1.684274 -1.074928)
			(stroke
				(width 0.1524)
				(type default)
			)
			(layer "F.SilkS")
		)
		(fp_line
			(start -0.381 -1.074928)
			(end 0 -0.625094)
			(stroke
				(width 0.1524)
				(type default)
			)
			(layer "F.SilkS")
		)
		(fp_line
			(start -1.684274 -1.074928)
			(end -0.381 -1.074928)
			(stroke
				(width 0.1524)
				(type default)
			)
			(layer "F.SilkS")
		)
		(fp_line
			(start 0 -0.625094)
			(end 0.381 -1.074928)
			(stroke
				(width 0.1524)
				(type default)
			)
			(layer "F.SilkS")
		)
		(fp_line
			(start 1.684274 1.074928)
			(end -1.684274 1.074928)
			(stroke
				(width 0.1524)
				(type default)
			)
			(layer "F.SilkS")
		)
		(fp_line
			(start -1.684274 1.074928)
			(end -1.684274 -1.074928)
			(stroke
				(width 0.1524)
				(type default)
			)
			(layer "F.SilkS")
		)
		(fp_poly
			(pts
				(xy -2.637282 -0.903986) (xy -2.637282 -0.395986) (xy -1.875282 -0.649986)
			)
			(stroke
				(width 0)
				(type default)
			)
			(fill yes)
			(layer "F.SilkS")
		)
		(fp_line
			(start 0.700024 -1.074928)
			(end -0.700024 -1.074928)
			(stroke
				(width 0.1)
				(type default)
			)
			(layer "F.Fab")
		)
		(fp_line
			(start -0.700024 -1.074928)
			(end -0.700024 1.074928)
			(stroke
				(width 0.1)
				(type default)
			)
			(layer "F.Fab")
		)
		(fp_line
			(start 0.700024 1.074928)
			(end 0.700024 -1.074928)
			(stroke
				(width 0.1)
				(type default)
			)
			(layer "F.Fab")
		)
		(fp_line
			(start -0.700024 1.074928)
			(end 0.700024 1.074928)
			(stroke
				(width 0.1)
				(type default)
			)
			(layer "F.Fab")
		)
		(fp_poly
			(pts
				(xy -2.637282 -0.903986) (xy -2.637282 -0.395986) (xy -1.875282 -0.649986)
			)
			(stroke
				(width 0)
				(type default)
			)
			(fill yes)
			(layer "F.Fab")
		)
		(pad "1" smd rect
			(at -1.100074 -0.649986)
			(size 0.4064 0.9144)
			(layers "F.Cu" "F.Mask" "F.Paste")
			(net "Net_1197")
		)
		(pad "2" smd rect
			(at -1.100074 0)
			(size 0.4064 0.9144)
			(layers "F.Cu" "F.Mask" "F.Paste")
			(net "RST_SPI_FLASH_R_N")
		)
		(pad "3" smd rect
			(at -1.100074 0.649986)
			(size 0.4064 0.9144)
			(layers "F.Cu" "F.Mask" "F.Paste")
			(net "GND")
		)
		(pad "4" smd rect
			(at 1.100074 0.649986)
			(size 0.4064 0.9144)
			(layers "F.Cu" "F.Mask" "F.Paste")
			(net "RST_SPI_FLASH_BUF_R3_N")
		)
		(pad "5" smd rect
			(at 1.100074 -0.649986)
			(size 0.4064 0.9144)
			(layers "F.Cu" "F.Mask" "F.Paste")
			(net "P3V3_AUX")
		)
	)
	(footprint ""
		(layer "F.Cu")
		(at 59.5884 -27.813 -90)
		(property "Reference" "R215"
			(at 0 0 270)
			(layer "F.SilkS")
			(hide yes)
			(effects
				(font
					(size 1.27 1.27)
				)
			)
		)
		(property "Value" ""
			(at 0 0 270)
			(layer "F.Fab")
			(effects
				(font
					(size 1.27 1.27)
				)
			)
		)
		(duplicate_pad_numbers_are_jumpers no)
		(fp_line
			(start -0.7874 0.4064)
			(end -0.7874 -0.4064)
			(stroke
				(width 0.1524)
				(type default)
			)
			(layer "F.SilkS")
		)
		(fp_line
			(start 0.7874 0.4064)
			(end -0.7874 0.4064)
			(stroke
				(width 0.1524)
				(type default)
			)
			(layer "F.SilkS")
		)
		(fp_line
			(start -0.7874 -0.4064)
			(end 0.7874 -0.4064)
			(stroke
				(width 0.1524)
				(type default)
			)
			(layer "F.SilkS")
		)
		(fp_line
			(start 0.7874 -0.4064)
			(end 0.7874 0.4064)
			(stroke
				(width 0.1524)
				(type default)
			)
			(layer "F.SilkS")
		)
		(fp_line
			(start -0.67945 0.3048)
			(end -0.67945 -0.305054)
			(stroke
				(width 0.1)
				(type default)
			)
			(layer "F.Fab")
		)
		(fp_line
			(start -0.12065 0.3048)
			(end -0.67945 0.3048)
			(stroke
				(width 0.1)
				(type default)
			)
			(layer "F.Fab")
		)
		(fp_line
			(start 0.120396 0.3048)
			(end 0.120396 0.2794)
			(stroke
				(width 0.1)
				(type default)
			)
			(layer "F.Fab")
		)
		(fp_line
			(start 0.67945 0.3048)
			(end 0.120396 0.3048)
			(stroke
				(width 0.1)
				(type default)
			)
			(layer "F.Fab")
		)
		(fp_line
			(start -0.12065 0.2794)
			(end -0.12065 0.3048)
			(stroke
				(width 0.1)
				(type default)
			)
			(layer "F.Fab")
		)
		(fp_line
			(start 0.120396 0.2794)
			(end -0.12065 0.2794)
			(stroke
				(width 0.1)
				(type default)
			)
			(layer "F.Fab")
		)
		(fp_line
			(start -0.12065 -0.2794)
			(end 0.12065 -0.2794)
			(stroke
				(width 0.1)
				(type default)
			)
			(layer "F.Fab")
		)
		(fp_line
			(start 0.12065 -0.2794)
			(end 0.12065 -0.3048)
			(stroke
				(width 0.1)
				(type default)
			)
			(layer "F.Fab")
		)
		(fp_line
			(start 0.12065 -0.3048)
			(end 0.67945 -0.3048)
			(stroke
				(width 0.1)
				(type default)
			)
			(layer "F.Fab")
		)
		(fp_line
			(start 0.67945 -0.3048)
			(end 0.67945 0.3048)
			(stroke
				(width 0.1)
				(type default)
			)
			(layer "F.Fab")
		)
		(fp_line
			(start -0.67945 -0.305054)
			(end -0.12065 -0.305054)
			(stroke
				(width 0.1)
				(type default)
			)
			(layer "F.Fab")
		)
		(fp_line
			(start -0.12065 -0.305054)
			(end -0.12065 -0.2794)
			(stroke
				(width 0.1)
				(type default)
			)
			(layer "F.Fab")
		)
		(pad "1" smd circle
			(at -0.40005 0 270)
			(size 0 0)
			(layers "F.Cu" "F.Mask" "F.Paste")
			(net "BMC_CLK_25M_R")
		)
		(pad "2" smd circle
			(at 0.40005 0 270)
			(size 0 0)
			(layers "F.Cu" "F.Mask" "F.Paste")
			(net "BMC_CLK_25M")
		)
	)
	(footprint ""
		(layer "F.Cu")
		(at 33.909 -40.2082 90)
		(property "Reference" "U43"
			(at -0.8128 -2.31013 90)
			(unlocked yes)
			(layer "F.SilkS")
			(effects
				(font
					(size 0.7874 0.5842)
					(thickness 0.1524)
				)
			)
		)
		(property "Value" ""
			(at 0 0 90)
			(layer "F.Fab")
			(effects
				(font
					(size 1.27 1.27)
				)
			)
		)
		(duplicate_pad_numbers_are_jumpers no)
		(fp_line
			(start 2.032 -1.525016)
			(end 2.032 1.525016)
			(stroke
				(width 0.1524)
				(type default)
			)
			(layer "F.SilkS")
		)
		(fp_line
			(start 0.635 -1.525016)
			(end 2.032 -1.525016)
			(stroke
				(width 0.1524)
				(type default)
			)
			(layer "F.SilkS")
		)
		(fp_line
			(start -0.635 -1.525016)
			(end 0 -0.889)
			(stroke
				(width 0.1524)
				(type default)
			)
			(layer "F.SilkS")
		)
		(fp_line
			(start -2.032 -1.525016)
			(end -0.635 -1.525016)
			(stroke
				(width 0.1524)
				(type default)
			)
			(layer "F.SilkS")
		)
		(fp_line
			(start 0 -0.889)
			(end 0.635 -1.525016)
			(stroke
				(width 0.1524)
				(type default)
			)
			(layer "F.SilkS")
		)
		(fp_line
			(start 2.032 1.525016)
			(end -2.032 1.525016)
			(stroke
				(width 0.1524)
				(type default)
			)
			(layer "F.SilkS")
		)
		(fp_line
			(start -2.032 1.525016)
			(end -2.032 -1.525016)
			(stroke
				(width 0.1524)
				(type default)
			)
			(layer "F.SilkS")
		)
		(fp_poly
			(pts
				(xy -2.9718 -1.33096) (xy -2.9718 -0.56896) (xy -2.2098 -0.94996)
			)
			(stroke
				(width 0)
				(type default)
			)
			(fill yes)
			(layer "F.SilkS")
		)
		(fp_line
			(start 0.87503 -1.525016)
			(end 0.87503 1.525016)
			(stroke
				(width 0.1)
				(type default)
			)
			(layer "F.Fab")
		)
		(fp_line
			(start -0.87503 -1.525016)
			(end 0.87503 -1.525016)
			(stroke
				(width 0.1)
				(type default)
			)
			(layer "F.Fab")
		)
		(fp_line
			(start 0.87503 1.525016)
			(end -0.87503 1.525016)
			(stroke
				(width 0.1)
				(type default)
			)
			(layer "F.Fab")
		)
		(fp_line
			(start -0.87503 1.525016)
			(end -0.87503 -1.525016)
			(stroke
				(width 0.1)
				(type default)
			)
			(layer "F.Fab")
		)
		(fp_poly
			(pts
				(xy -2.9718 -1.33096) (xy -2.9718 -0.56896) (xy -2.2098 -0.94996)
			)
			(stroke
				(width 0)
				(type default)
			)
			(fill yes)
			(layer "F.Fab")
		)
		(pad "1" smd rect
			(at -1.35001 -0.94996)
			(size 0.6096 1.0668)
			(layers "F.Cu" "F.Mask" "F.Paste")
			(net "PWRGD_P1V0_AUX_DELAY_R1")
		)
		(pad "2" smd rect
			(at -1.35001 0)
			(size 0.6096 1.0668)
			(layers "F.Cu" "F.Mask" "F.Paste")
			(net "GND")
		)
		(pad "3" smd rect
			(at -1.35001 0.94996)
			(size 0.6096 1.0668)
			(layers "F.Cu" "F.Mask" "F.Paste")
			(net "PWRGD_P1V0_AUX_R2")
		)
		(pad "4" smd rect
			(at 1.35001 0.94996)
			(size 0.6096 1.0668)
			(layers "F.Cu" "F.Mask" "F.Paste")
			(net "U43_CT")
		)
		(pad "5" smd rect
			(at 1.35001 0)
			(size 0.6096 1.0668)
			(layers "F.Cu" "F.Mask" "F.Paste")
			(net "P1V0_AUX")
		)
		(pad "6" smd rect
			(at 1.35001 -0.94996)
			(size 0.6096 1.0668)
			(layers "F.Cu" "F.Mask" "F.Paste")
			(net "P3V3_AUX")
		)
	)
)
